(kicad_pcb
	(version 20260206)
	(generator "pcbnew")
	(generator_version "10.0")
	(general
		(thickness 1.6)
		(legacy_teardrops no)
	)
	(paper "A4")
	(title_block
		(title "v1-chassis-manager — T6M_CM_d_v01_1031_1645.brd")
		(comment 1 "Open CloudServer (Microsoft) / footprints 2023-2032 of 2512")
	)
	(layers
		(0 "F.Cu" signal "TOP")
		(4 "In1.Cu" signal "GND1")
		(6 "In2.Cu" signal "IN1")
		(8 "In3.Cu" signal "VCC1")
		(10 "In4.Cu" signal "VCC2")
		(12 "In5.Cu" signal "GND2")
		(14 "In6.Cu" signal "IN2")
		(16 "In7.Cu" signal "IN3")
		(18 "In8.Cu" signal "GND3")
		(2 "B.Cu" signal "BOTTOM")
		(9 "F.Adhes" user "F.Adhesive")
		(11 "B.Adhes" user "B.Adhesive")
		(13 "F.Paste" user "Package Geometry/Pastemask Top")
		(15 "B.Paste" user "Package Geometry/Pastemask Bottom")
		(5 "F.SilkS" user "Ref Des/Silkscreen Top")
		(7 "B.SilkS" user "Ref Des/Silkscreen Bottom")
		(1 "F.Mask" user "Board Geometry/Soldermask Top")
		(3 "B.Mask" user "Board Geometry/Soldermask Bottom")
		(17 "Dwgs.User" user "User.Drawings")
		(19 "Cmts.User" user "User.Comments")
		(21 "Eco1.User" user "User.Eco1")
		(23 "Eco2.User" user "User.Eco2")
		(25 "Edge.Cuts" user "Board Geometry/Outline")
		(27 "Margin" user)
		(31 "F.CrtYd" user "Package Geometry/Place Bound Top")
		(29 "B.CrtYd" user "Package Geometry/Place Bound Bottom")
		(35 "F.Fab" user "Ref Des/Assembly Top")
		(33 "B.Fab" user "Ref Des/Assembly Bottom")
	)
	(footprint ""
		(layer "B.Cu")
		(at 114.092482 -164.891466 -90)
		(property "Reference" "R774"
			(at 3.178048 2.394458 270)
			(unlocked yes)
			(layer "B.SilkS")
			(effects
				(font
					(size 0.7874 0.5842)
					(thickness 0.1524)
				)
				(justify left mirror)
			)
		)
		(property "Value" ""
			(at 0 0 90)
			(layer "B.Fab")
			(effects
				(font
					(size 1.27 1.27)
				)
				(justify mirror)
			)
		)
		(duplicate_pad_numbers_are_jumpers no)
		(fp_line
			(start -0.7874 0.4064)
			(end 0.7874 0.4064)
			(stroke
				(width 0.1524)
				(type default)
			)
			(layer "B.SilkS")
		)
		(fp_line
			(start 0.7874 0.4064)
			(end 0.7874 -0.4064)
			(stroke
				(width 0.1524)
				(type default)
			)
			(layer "B.SilkS")
		)
		(fp_line
			(start -0.7874 -0.4064)
			(end -0.7874 0.4064)
			(stroke
				(width 0.1524)
				(type default)
			)
			(layer "B.SilkS")
		)
		(fp_line
			(start 0.7874 -0.4064)
			(end -0.7874 -0.4064)
			(stroke
				(width 0.1524)
				(type default)
			)
			(layer "B.SilkS")
		)
		(fp_poly
			(pts
				(xy 0.508 0.2794) (xy 0.508 0.2286) (xy 0.635 0.2286) (xy 0.635 -0.254) (xy 0.5334 -0.254) (xy 0.5334 -0.2794)
				(xy -0.5334 -0.2794) (xy -0.5334 -0.254) (xy -0.635 -0.254) (xy -0.635 0.254) (xy -0.5334 0.254)
				(xy -0.5334 0.2794)
			)
			(stroke
				(width 0)
				(type default)
			)
			(fill no)
			(layer "B.CrtYd")
		)
		(pad "1" smd rect
			(at -0.40005 0 90)
			(size 0.4572 0.508)
			(layers "B.Cu" "B.Mask" "B.Paste")
			(net "I2C_SDA_FANCTRL2_R")
		)
		(pad "2" smd rect
			(at 0.40005 0 90)
			(size 0.4572 0.508)
			(layers "B.Cu" "B.Mask" "B.Paste")
			(net "I2C_COM3_SDA")
		)
	)
	(footprint ""
		(layer "B.Cu")
		(at 45.712634 -133.130798)
		(property "Reference" "R260"
			(at 4.766818 0.385826 0)
			(unlocked yes)
			(layer "B.SilkS")
			(effects
				(font
					(size 0.7874 0.5842)
					(thickness 0.1524)
				)
				(justify left mirror)
			)
		)
		(property "Value" ""
			(at 0 0 0)
			(layer "B.Fab")
			(effects
				(font
					(size 1.27 1.27)
				)
				(justify mirror)
			)
		)
		(duplicate_pad_numbers_are_jumpers no)
		(fp_line
			(start -0.7874 -0.4064)
			(end -0.7874 0.4064)
			(stroke
				(width 0.1524)
				(type default)
			)
			(layer "B.SilkS")
		)
		(fp_line
			(start -0.7874 0.4064)
			(end 0.7874 0.4064)
			(stroke
				(width 0.1524)
				(type default)
			)
			(layer "B.SilkS")
		)
		(fp_line
			(start 0.7874 -0.4064)
			(end -0.7874 -0.4064)
			(stroke
				(width 0.1524)
				(type default)
			)
			(layer "B.SilkS")
		)
		(fp_line
			(start 0.7874 0.4064)
			(end 0.7874 -0.4064)
			(stroke
				(width 0.1524)
				(type default)
			)
			(layer "B.SilkS")
		)
		(fp_poly
			(pts
				(xy 0.508 0.2794) (xy 0.508 0.2286) (xy 0.635 0.2286) (xy 0.635 -0.254) (xy 0.5334 -0.254) (xy 0.5334 -0.2794)
				(xy -0.5334 -0.2794) (xy -0.5334 -0.254) (xy -0.635 -0.254) (xy -0.635 0.254) (xy -0.5334 0.254)
				(xy -0.5334 0.2794)
			)
			(stroke
				(width 0)
				(type default)
			)
			(fill no)
			(layer "B.CrtYd")
		)
		(pad "1" smd rect
			(at -0.40005 0 180)
			(size 0.4572 0.508)
			(layers "B.Cu" "B.Mask" "B.Paste")
			(net "BMC_NODE1_DDR3_ZQ")
		)
		(pad "2" smd rect
			(at 0.40005 0 180)
			(size 0.4572 0.508)
			(layers "B.Cu" "B.Mask" "B.Paste")
			(net "GND")
		)
	)
	(footprint ""
		(layer "B.Cu")
		(at 154.594814 -67.232022 90)
		(property "Reference" "C359"
			(at 0.02159 5.137912 270)
			(unlocked yes)
			(layer "B.SilkS")
			(effects
				(font
					(size 0.7874 0.5842)
					(thickness 0.1524)
				)
				(justify left mirror)
			)
		)
		(property "Value" ""
			(at 0 0 90)
			(layer "B.Fab")
			(effects
				(font
					(size 1.27 1.27)
				)
				(justify mirror)
			)
		)
		(duplicate_pad_numbers_are_jumpers no)
		(fp_line
			(start 0.7874 -0.4064)
			(end -0.7874 -0.4064)
			(stroke
				(width 0.1524)
				(type default)
			)
			(layer "B.SilkS")
		)
		(fp_line
			(start -0.7874 -0.4064)
			(end -0.7874 0.4064)
			(stroke
				(width 0.1524)
				(type default)
			)
			(layer "B.SilkS")
		)
		(fp_line
			(start 0 0.381)
			(end 0 -0.381)
			(stroke
				(width 0.1524)
				(type default)
			)
			(layer "B.SilkS")
		)
		(fp_line
			(start 0.7874 0.4064)
			(end 0.7874 -0.4064)
			(stroke
				(width 0.1524)
				(type default)
			)
			(layer "B.SilkS")
		)
		(fp_line
			(start -0.7874 0.4064)
			(end 0.7874 0.4064)
			(stroke
				(width 0.1524)
				(type default)
			)
			(layer "B.SilkS")
		)
		(fp_poly
			(pts
				(xy 0.5334 0.254) (xy 0.635 0.254) (xy 0.635 0.2286) (xy 0.635 -0.254) (xy 0.5334 -0.254) (xy 0.5334 -0.2794)
				(xy -0.5334 -0.2794) (xy -0.5334 -0.254) (xy -0.635 -0.254) (xy -0.635 0.254) (xy -0.5334 0.254)
				(xy -0.5334 0.2794) (xy 0.508 0.2794) (xy 0.5334 0.2794)
			)
			(stroke
				(width 0)
				(type default)
			)
			(fill no)
			(layer "B.CrtYd")
		)
		(pad "1" smd rect
			(at -0.40005 0 270)
			(size 0.4572 0.508)
			(layers "B.Cu" "B.Mask" "B.Paste")
			(net "P1V8_SATA_VAA1_NODE1")
		)
		(pad "2" smd rect
			(at 0.40005 0 270)
			(size 0.4572 0.508)
			(layers "B.Cu" "B.Mask" "B.Paste")
			(net "GND")
		)
	)
	(footprint ""
		(layer "B.Cu")
		(at 106.588052 -173.118526 180)
		(property "Reference" "C571"
			(at -1.49987 -1.106424 0)
			(unlocked yes)
			(layer "B.SilkS")
			(effects
				(font
					(size 0.7874 0.5842)
					(thickness 0.1524)
				)
				(justify left mirror)
			)
		)
		(property "Value" ""
			(at 0 0 0)
			(layer "B.Fab")
			(effects
				(font
					(size 1.27 1.27)
				)
				(justify mirror)
			)
		)
		(duplicate_pad_numbers_are_jumpers no)
		(fp_line
			(start 0.7874 0.4064)
			(end 0.7874 -0.4064)
			(stroke
				(width 0.1524)
				(type default)
			)
			(layer "B.SilkS")
		)
		(fp_line
			(start 0.7874 -0.4064)
			(end -0.7874 -0.4064)
			(stroke
				(width 0.1524)
				(type default)
			)
			(layer "B.SilkS")
		)
		(fp_line
			(start 0 0.381)
			(end 0 -0.381)
			(stroke
				(width 0.1524)
				(type default)
			)
			(layer "B.SilkS")
		)
		(fp_line
			(start -0.7874 0.4064)
			(end 0.7874 0.4064)
			(stroke
				(width 0.1524)
				(type default)
			)
			(layer "B.SilkS")
		)
		(fp_line
			(start -0.7874 -0.4064)
			(end -0.7874 0.4064)
			(stroke
				(width 0.1524)
				(type default)
			)
			(layer "B.SilkS")
		)
		(fp_poly
			(pts
				(xy 0.5334 0.254) (xy 0.635 0.254) (xy 0.635 0.2286) (xy 0.635 -0.254) (xy 0.5334 -0.254) (xy 0.5334 -0.2794)
				(xy -0.5334 -0.2794) (xy -0.5334 -0.254) (xy -0.635 -0.254) (xy -0.635 0.254) (xy -0.5334 0.254)
				(xy -0.5334 0.2794) (xy 0.508 0.2794) (xy 0.5334 0.2794)
			)
			(stroke
				(width 0)
				(type default)
			)
			(fill no)
			(layer "B.CrtYd")
		)
		(pad "1" smd rect
			(at -0.40005 0)
			(size 0.4572 0.508)
			(layers "B.Cu" "B.Mask" "B.Paste")
			(net "GND")
		)
		(pad "2" smd rect
			(at 0.40005 0)
			(size 0.4572 0.508)
			(layers "B.Cu" "B.Mask" "B.Paste")
			(net "P3V3_NODE1")
		)
	)
	(footprint ""
		(layer "B.Cu")
		(at 140.760196 -61.82233)
		(property "Reference" "C353"
			(at -4.939792 0.007874 0)
			(unlocked yes)
			(layer "B.SilkS")
			(effects
				(font
					(size 0.7874 0.5842)
					(thickness 0.1524)
				)
				(justify left mirror)
			)
		)
		(property "Value" ""
			(at 0 0 0)
			(layer "B.Fab")
			(effects
				(font
					(size 1.27 1.27)
				)
				(justify mirror)
			)
		)
		(duplicate_pad_numbers_are_jumpers no)
		(fp_line
			(start -0.7874 -0.4064)
			(end -0.7874 0.4064)
			(stroke
				(width 0.1524)
				(type default)
			)
			(layer "B.SilkS")
		)
		(fp_line
			(start -0.7874 0.4064)
			(end 0.7874 0.4064)
			(stroke
				(width 0.1524)
				(type default)
			)
			(layer "B.SilkS")
		)
		(fp_line
			(start 0 0.381)
			(end 0 -0.381)
			(stroke
				(width 0.1524)
				(type default)
			)
			(layer "B.SilkS")
		)
		(fp_line
			(start 0.7874 -0.4064)
			(end -0.7874 -0.4064)
			(stroke
				(width 0.1524)
				(type default)
			)
			(layer "B.SilkS")
		)
		(fp_line
			(start 0.7874 0.4064)
			(end 0.7874 -0.4064)
			(stroke
				(width 0.1524)
				(type default)
			)
			(layer "B.SilkS")
		)
		(fp_poly
			(pts
				(xy 0.5334 0.254) (xy 0.635 0.254) (xy 0.635 0.2286) (xy 0.635 -0.254) (xy 0.5334 -0.254) (xy 0.5334 -0.2794)
				(xy -0.5334 -0.2794) (xy -0.5334 -0.254) (xy -0.635 -0.254) (xy -0.635 0.254) (xy -0.5334 0.254)
				(xy -0.5334 0.2794) (xy 0.508 0.2794) (xy 0.5334 0.2794)
			)
			(stroke
				(width 0)
				(type default)
			)
			(fill no)
			(layer "B.CrtYd")
		)
		(pad "1" smd rect
			(at -0.40005 0 180)
			(size 0.4572 0.508)
			(layers "B.Cu" "B.Mask" "B.Paste")
			(net "P3V3_NODE1")
		)
		(pad "2" smd rect
			(at 0.40005 0 180)
			(size 0.4572 0.508)
			(layers "B.Cu" "B.Mask" "B.Paste")
			(net "GND")
		)
	)
	(footprint ""
		(layer "B.Cu")
		(at 57.158636 -138.163046 90)
		(property "Reference" "C271"
			(at 1.7653 -1.199134 270)
			(unlocked yes)
			(layer "B.SilkS")
			(effects
				(font
					(size 0.7874 0.5842)
					(thickness 0.1524)
				)
				(justify mirror)
			)
		)
		(property "Value" ""
			(at 0 0 90)
			(layer "B.Fab")
			(effects
				(font
					(size 1.27 1.27)
				)
				(justify mirror)
			)
		)
		(duplicate_pad_numbers_are_jumpers no)
		(fp_line
			(start 1.2954 -0.5842)
			(end -1.2954 -0.5842)
			(stroke
				(width 0.1524)
				(type default)
			)
			(layer "B.SilkS")
		)
		(fp_line
			(start 0 -0.5842)
			(end 0 0.5842)
			(stroke
				(width 0.1524)
				(type default)
			)
			(layer "B.SilkS")
		)
		(fp_line
			(start -1.2954 -0.5842)
			(end -1.2954 0.5842)
			(stroke
				(width 0.1524)
				(type default)
			)
			(layer "B.SilkS")
		)
		(fp_line
			(start 1.2954 0.5842)
			(end 1.2954 -0.5842)
			(stroke
				(width 0.1524)
				(type default)
			)
			(layer "B.SilkS")
		)
		(fp_line
			(start -1.2954 0.5842)
			(end 1.2954 0.5842)
			(stroke
				(width 0.1524)
				(type default)
			)
			(layer "B.SilkS")
		)
		(fp_poly
			(pts
				(xy -0.8636 -0.4572) (xy -0.8636 -0.3556) (xy -1.143 -0.3556) (xy -1.143 0.3556) (xy -0.8636 0.3556)
				(xy -0.8636 0.4572) (xy 0.8636 0.4572) (xy 0.8636 0.3556) (xy 1.143 0.3556) (xy 1.143 -0.3556) (xy 0.8636 -0.3556)
				(xy 0.8636 -0.4572)
			)
			(stroke
				(width 0)
				(type default)
			)
			(fill no)
			(layer "B.CrtYd")
		)
		(fp_line
			(start 0.884936 -0.504952)
			(end -0.884936 -0.504952)
			(stroke
				(width 0.1)
				(type default)
			)
			(layer "B.Fab")
		)
		(fp_line
			(start -0.884936 -0.504952)
			(end -0.884936 0.504952)
			(stroke
				(width 0.1)
				(type default)
			)
			(layer "B.Fab")
		)
		(fp_line
			(start 0.884936 0.504952)
			(end 0.884936 -0.504952)
			(stroke
				(width 0.1)
				(type default)
			)
			(layer "B.Fab")
		)
		(fp_line
			(start -0.884936 0.504952)
			(end 0.884936 0.504952)
			(stroke
				(width 0.1)
				(type default)
			)
			(layer "B.Fab")
		)
		(pad "1" smd rect
			(at -0.7366 0 180)
			(size 0.7112 0.8128)
			(layers "B.Cu" "B.Mask" "B.Paste")
			(net "P1V538_BMC_NODE1")
		)
		(pad "2" smd rect
			(at 0.7366 0 180)
			(size 0.7112 0.8128)
			(layers "B.Cu" "B.Mask" "B.Paste")
			(net "GND")
		)
	)
	(footprint ""
		(layer "B.Cu")
		(at 66.076322 -69.607684 90)
		(property "Reference" "C115"
			(at -34.680398 -13.222732 270)
			(unlocked yes)
			(layer "B.SilkS")
			(effects
				(font
					(size 0.7874 0.5842)
					(thickness 0.1524)
				)
				(justify left mirror)
			)
		)
		(property "Value" ""
			(at 0 0 90)
			(layer "B.Fab")
			(effects
				(font
					(size 1.27 1.27)
				)
				(justify mirror)
			)
		)
		(duplicate_pad_numbers_are_jumpers no)
		(fp_line
			(start 0.7874 -0.4064)
			(end -0.7874 -0.4064)
			(stroke
				(width 0.1524)
				(type default)
			)
			(layer "B.SilkS")
		)
		(fp_line
			(start -0.7874 -0.4064)
			(end -0.7874 0.4064)
			(stroke
				(width 0.1524)
				(type default)
			)
			(layer "B.SilkS")
		)
		(fp_line
			(start 0 0.381)
			(end 0 -0.381)
			(stroke
				(width 0.1524)
				(type default)
			)
			(layer "B.SilkS")
		)
		(fp_line
			(start 0.7874 0.4064)
			(end 0.7874 -0.4064)
			(stroke
				(width 0.1524)
				(type default)
			)
			(layer "B.SilkS")
		)
		(fp_line
			(start -0.7874 0.4064)
			(end 0.7874 0.4064)
			(stroke
				(width 0.1524)
				(type default)
			)
			(layer "B.SilkS")
		)
		(fp_poly
			(pts
				(xy 0.5334 0.254) (xy 0.635 0.254) (xy 0.635 0.2286) (xy 0.635 -0.254) (xy 0.5334 -0.254) (xy 0.5334 -0.2794)
				(xy -0.5334 -0.2794) (xy -0.5334 -0.254) (xy -0.635 -0.254) (xy -0.635 0.254) (xy -0.5334 0.254)
				(xy -0.5334 0.2794) (xy 0.508 0.2794) (xy 0.5334 0.2794)
			)
			(stroke
				(width 0)
				(type default)
			)
			(fill no)
			(layer "B.CrtYd")
		)
		(pad "1" smd rect
			(at -0.40005 0 270)
			(size 0.4572 0.508)
			(layers "B.Cu" "B.Mask" "B.Paste")
			(net "PV_VDDR_NODE1")
		)
		(pad "2" smd rect
			(at 0.40005 0 270)
			(size 0.4572 0.508)
			(layers "B.Cu" "B.Mask" "B.Paste")
			(net "GND")
		)
	)
	(footprint ""
		(layer "B.Cu")
		(at 134.22376 -184.951624 90)
		(property "Reference" "R959"
			(at 4.357624 -1.658874 270)
			(unlocked yes)
			(layer "B.SilkS")
			(effects
				(font
					(size 0.7874 0.5842)
					(thickness 0.1524)
				)
				(justify left mirror)
			)
		)
		(property "Value" ""
			(at 0 0 90)
			(layer "B.Fab")
			(effects
				(font
					(size 1.27 1.27)
				)
				(justify mirror)
			)
		)
		(duplicate_pad_numbers_are_jumpers no)
		(fp_line
			(start 0.7874 -0.4064)
			(end -0.7874 -0.4064)
			(stroke
				(width 0.1524)
				(type default)
			)
			(layer "B.SilkS")
		)
		(fp_line
			(start -0.7874 -0.4064)
			(end -0.7874 0.4064)
			(stroke
				(width 0.1524)
				(type default)
			)
			(layer "B.SilkS")
		)
		(fp_line
			(start 0.7874 0.4064)
			(end 0.7874 -0.4064)
			(stroke
				(width 0.1524)
				(type default)
			)
			(layer "B.SilkS")
		)
		(fp_line
			(start -0.7874 0.4064)
			(end 0.7874 0.4064)
			(stroke
				(width 0.1524)
				(type default)
			)
			(layer "B.SilkS")
		)
		(fp_poly
			(pts
				(xy 0.508 0.2794) (xy 0.508 0.2286) (xy 0.635 0.2286) (xy 0.635 -0.254) (xy 0.5334 -0.254) (xy 0.5334 -0.2794)
				(xy -0.5334 -0.2794) (xy -0.5334 -0.254) (xy -0.635 -0.254) (xy -0.635 0.254) (xy -0.5334 0.254)
				(xy -0.5334 0.2794)
			)
			(stroke
				(width 0)
				(type default)
			)
			(fill no)
			(layer "B.CrtYd")
		)
		(pad "1" smd rect
			(at -0.40005 0 270)
			(size 0.4572 0.508)
			(layers "B.Cu" "B.Mask" "B.Paste")
			(net "UART_T9_NODE1_TXD")
		)
		(pad "2" smd rect
			(at 0.40005 0 270)
			(size 0.4572 0.508)
			(layers "B.Cu" "B.Mask" "B.Paste")
			(net "UART_T9_NODE1_TXD_R")
		)
	)
	(footprint ""
		(layer "B.Cu")
		(at 23.847298 -113.015522)
		(property "Reference" "C54"
			(at -2.11963 -0.579374 0)
			(unlocked yes)
			(layer "B.SilkS")
			(effects
				(font
					(size 0.7874 0.5842)
					(thickness 0.1524)
				)
				(justify left mirror)
			)
		)
		(property "Value" ""
			(at 0 0 0)
			(layer "B.Fab")
			(effects
				(font
					(size 1.27 1.27)
				)
				(justify mirror)
			)
		)
		(duplicate_pad_numbers_are_jumpers no)
		(fp_line
			(start -1.905 -0.8636)
			(end -1.905 0.8636)
			(stroke
				(width 0.1524)
				(type default)
			)
			(layer "B.SilkS")
		)
		(fp_line
			(start -1.905 0.8636)
			(end 1.905 0.8636)
			(stroke
				(width 0.1524)
				(type default)
			)
			(layer "B.SilkS")
		)
		(fp_line
			(start 0 0.8382)
			(end 0 -0.8382)
			(stroke
				(width 0.1524)
				(type default)
			)
			(layer "B.SilkS")
		)
		(fp_line
			(start 1.905 -0.8636)
			(end -1.905 -0.8636)
			(stroke
				(width 0.1524)
				(type default)
			)
			(layer "B.SilkS")
		)
		(fp_line
			(start 1.905 0.8636)
			(end 1.905 -0.8636)
			(stroke
				(width 0.1524)
				(type default)
			)
			(layer "B.SilkS")
		)
		(fp_rect
			(start 1.524 0.7366)
			(end -1.524 -0.7366)
			(stroke
				(width 0)
				(type default)
			)
			(fill no)
			(layer "B.CrtYd")
		)
		(pad "1" smd rect
			(at -0.94996 0 180)
			(size 1.1176 1.3716)
			(layers "B.Cu" "B.Mask" "B.Paste")
			(net "P1V05_NODE1")
		)
		(pad "2" smd rect
			(at 0.94996 0 180)
			(size 1.1176 1.3716)
			(layers "B.Cu" "B.Mask" "B.Paste")
			(net "GND")
		)
	)
	(footprint ""
		(layer "B.Cu")
		(at 18.28038 -90.893392 -90)
		(property "Reference" ""
			(at 0 0 90)
			(layer "B.SilkS")
			(hide yes)
			(effects
				(font
					(size 1.27 1.27)
				)
				(justify mirror)
			)
		)
		(property "Value" ""
			(at 0 0 90)
			(layer "B.Fab")
			(effects
				(font
					(size 1.27 1.27)
				)
				(justify mirror)
			)
		)
		(duplicate_pad_numbers_are_jumpers no)
		(fp_poly
			(pts
				(arc
					(start 0 -1.4986)
					(mid 0 1.4986)
					(end 0 -1.4986)
				)
			)
			(stroke
				(width 0)
				(type default)
			)
			(fill no)
			(layer "B.CrtYd")
		)
		(pad "1" smd circle
			(at 0 0 90)
			(size 0.9906 0.9906)
			(layers "B.Cu" "B.Mask" "B.Paste")
			(net "Net_29")
		)
		(zone
			(layer "B.Cu")
			(hatch none 0.5)
			(connect_pads
				(clearance 0)
			)
			(min_thickness 0.25)
			(keepout
				(tracks not_allowed)
				(vias allowed)
				(pads allowed)
				(copperpour not_allowed)
				(footprints allowed)
			)
			(placement
				(enabled no)
				(sheetname "")
			)
			(fill
				(thermal_gap 0.5)
				(thermal_bridge_width 0.5)
				(island_removal_mode 0)
			)
			(polygon
				(pts
					(arc
						(start 19.90598 -90.893392)
						(mid 16.65478 -90.893392)
						(end 19.90598 -90.893392)
					)
				)
			)
		)
	)
)
